(kicad_pcb
	(version 20241229)
	(generator "pcbnew")
	(generator_version "9.0")
	(general
		(thickness 1.62)
		(legacy_teardrops no)
	)
	(paper "A3")
	(title_block
		(title "COM Express 7 Baseboard")
		(date "2025-02-04")
		(rev "1.1.2")
		(company "Antmicro Ltd")
		(comment 1 "www.antmicro.com")
		(comment 9 "footprints 576-580 of 802")
	)
	(layers
		(0 "F.Cu" signal)
		(4 "In1.Cu" signal)
		(6 "In2.Cu" signal)
		(8 "In3.Cu" signal)
		(10 "In4.Cu" signal)
		(12 "In5.Cu" signal)
		(14 "In6.Cu" signal)
		(2 "B.Cu" signal)
		(9 "F.Adhes" user "F.Adhesive")
		(11 "B.Adhes" user "B.Adhesive")
		(13 "F.Paste" user)
		(15 "B.Paste" user)
		(5 "F.SilkS" user "F.Silkscreen")
		(7 "B.SilkS" user "B.Silkscreen")
		(1 "F.Mask" user)
		(3 "B.Mask" user)
		(17 "Dwgs.User" user "User.Drawings")
		(19 "Cmts.User" user "User.Comments")
		(21 "Eco1.User" user "User.Eco1")
		(23 "Eco2.User" user "User.Eco2")
		(25 "Edge.Cuts" user)
		(27 "Margin" user)
		(31 "F.CrtYd" user "F.Courtyard")
		(29 "B.CrtYd" user "B.Courtyard")
		(35 "F.Fab" user)
		(33 "B.Fab" user)
	)
	(footprint "antmicro-footprints:C_0402_1005Metric"
		(layer "B.Cu")
		(at 121.5 73.61 -90)
		(descr "Capacitor SMD 0402")
		(tags "capacitor SMD 0402")
		(property "Reference" "C35"
			(at -1.1 -1.35 90)
			(layer "B.SilkS")
			(effects
				(font
					(size 0.7 0.7)
					(thickness 0.15)
				)
				(justify left bottom mirror)
			)
		)
		(property "Value" "C_100n_0402"
			(at -1.022927 -2.155213 90)
			(layer "B.Fab")
			(effects
				(font
					(size 0.7 0.7)
					(thickness 0.15)
				)
				(justify left bottom mirror)
			)
		)
		(property "Datasheet" "https://www.murata.com/products/productdetail?partno=GRM155R61H104KE14%23"
			(at 0 0 270)
			(layer "F.Fab")
			(hide yes)
			(effects
				(font
					(size 1.27 1.27)
					(thickness 0.15)
				)
			)
		)
		(property "Author" "Antmicro"
			(at 47.89 195.11 0)
			(layer "B.Fab")
			(hide yes)
			(effects
				(font
					(size 1 1)
					(thickness 0.15)
				)
				(justify mirror)
			)
		)
		(property "Dielectric" "X5R"
			(at 47.89 195.11 0)
			(layer "B.Fab")
			(hide yes)
			(effects
				(font
					(size 1 1)
					(thickness 0.15)
				)
				(justify mirror)
			)
		)
		(property "License" "Apache-2.0"
			(at 47.89 195.11 0)
			(layer "B.Fab")
			(hide yes)
			(effects
				(font
					(size 1 1)
					(thickness 0.15)
				)
				(justify mirror)
			)
		)
		(property "MPN" "GRM155R61H104KE14D"
			(at 47.89 195.11 0)
			(layer "B.Fab")
			(hide yes)
			(effects
				(font
					(size 1 1)
					(thickness 0.15)
				)
				(justify mirror)
			)
		)
		(property "Manufacturer" "Murata"
			(at 47.89 195.11 0)
			(layer "B.Fab")
			(hide yes)
			(effects
				(font
					(size 1 1)
					(thickness 0.15)
				)
				(justify mirror)
			)
		)
		(property "Public" "False"
			(at 47.89 195.11 0)
			(layer "B.Fab")
			(hide yes)
			(effects
				(font
					(size 1 1)
					(thickness 0.15)
				)
				(justify mirror)
			)
		)
		(property "Val" "100n"
			(at 47.89 195.11 0)
			(layer "B.Fab")
			(hide yes)
			(effects
				(font
					(size 1 1)
					(thickness 0.15)
				)
				(justify mirror)
			)
		)
		(property "Voltage" "50V"
			(at 47.89 195.11 0)
			(layer "B.Fab")
			(hide yes)
			(effects
				(font
					(size 1 1)
					(thickness 0.15)
				)
				(justify mirror)
			)
		)
		(sheetname "USB-C console")
		(sheetfile "usb-c_console.kicad_sch")
		(attr smd)
		(fp_rect
			(start -0.925 0.47)
			(end 0.925 -0.47)
			(stroke
				(width 0.05)
				(type default)
			)
			(fill no)
			(layer "B.CrtYd")
		)
		(fp_line
			(start -0.494 0.25)
			(end -0.494 -0.248)
			(stroke
				(width 0.15)
				(type solid)
			)
			(layer "B.Fab")
		)
		(fp_line
			(start 0.504 0.25)
			(end -0.494 0.25)
			(stroke
				(width 0.15)
				(type solid)
			)
			(layer "B.Fab")
		)
		(fp_line
			(start -0.494 -0.248)
			(end 0.504 -0.248)
			(stroke
				(width 0.15)
				(type solid)
			)
			(layer "B.Fab")
		)
		(fp_line
			(start 0.504 -0.248)
			(end 0.504 0.25)
			(stroke
				(width 0.15)
				(type solid)
			)
			(layer "B.Fab")
		)
		(pad "1" smd roundrect
			(at -0.48 0 270)
			(size 0.59 0.64)
			(layers "B.Cu" "B.Mask" "B.Paste")
			(roundrect_rratio 0.25)
			(net 1 "GND")
			(pintype "passive")
			(teardrops
				(best_length_ratio 0.2)
				(max_length 1)
				(best_width_ratio 0.9)
				(max_width 2)
				(curved_edges yes)
				(filter_ratio 0.9)
				(enabled yes)
				(allow_two_segments yes)
				(prefer_zone_connections yes)
			)
		)
		(pad "2" smd roundrect
			(at 0.48 0 270)
			(size 0.59 0.64)
			(layers "B.Cu" "B.Mask" "B.Paste")
			(roundrect_rratio 0.25)
			(net 2 "+3V3")
			(pintype "passive")
			(teardrops
				(best_length_ratio 0.2)
				(max_length 1)
				(best_width_ratio 0.9)
				(max_width 2)
				(curved_edges yes)
				(filter_ratio 0.9)
				(enabled yes)
				(allow_two_segments yes)
				(prefer_zone_connections yes)
			)
		)
	)
	(footprint "antmicro-footprints:R_0402_1005Metric"
		(layer "B.Cu")
		(at 126.09 141.06)
		(descr "Resistor SMD 0402")
		(tags "resistor SMD 0402")
		(property "Reference" "R292"
			(at -3.64 1.1 0)
			(layer "B.SilkS")
			(effects
				(font
					(size 0.7 0.7)
					(thickness 0.15)
				)
				(justify right bottom mirror)
			)
		)
		(property "Value" "R_10k_0402"
			(at -1.011843 -1.772047 0)
			(layer "B.Fab")
			(effects
				(font
					(size 0.7 0.7)
					(thickness 0.15)
				)
				(justify right bottom mirror)
			)
		)
		(property "Datasheet" "https://www.bourns.com/docs/product-datasheets/cr.pdf"
			(at 0 0 0)
			(layer "F.Fab")
			(hide yes)
			(effects
				(font
					(size 1.27 1.27)
					(thickness 0.15)
				)
			)
		)
		(property "Author" "Antmicro"
			(at 0 0 0)
			(layer "B.Fab")
			(hide yes)
			(effects
				(font
					(size 1 1)
					(thickness 0.15)
				)
				(justify mirror)
			)
		)
		(property "License" "Apache-2.0"
			(at 0 0 0)
			(layer "B.Fab")
			(hide yes)
			(effects
				(font
					(size 1 1)
					(thickness 0.15)
				)
				(justify mirror)
			)
		)
		(property "MPN" "CR0402-FX-1002GLF"
			(at 0 0 0)
			(layer "B.Fab")
			(hide yes)
			(effects
				(font
					(size 1 1)
					(thickness 0.15)
				)
				(justify mirror)
			)
		)
		(property "Manufacturer" "Bourns"
			(at 0 0 0)
			(layer "B.Fab")
			(hide yes)
			(effects
				(font
					(size 1 1)
					(thickness 0.15)
				)
				(justify mirror)
			)
		)
		(property "Public" "False"
			(at 0 0 0)
			(layer "B.Fab")
			(hide yes)
			(effects
				(font
					(size 1 1)
					(thickness 0.15)
				)
				(justify mirror)
			)
		)
		(property "Tolerance" "1%"
			(at 0 0 0)
			(layer "B.Fab")
			(hide yes)
			(effects
				(font
					(size 1 1)
					(thickness 0.15)
				)
				(justify mirror)
			)
		)
		(property "Val" "10k"
			(at 0 0 0)
			(layer "B.Fab")
			(hide yes)
			(effects
				(font
					(size 1 1)
					(thickness 0.15)
				)
				(justify mirror)
			)
		)
		(sheetname "KR to SFI #2")
		(sheetfile "kr_sfi.kicad_sch")
		(attr smd)
		(fp_rect
			(start -0.925 0.47)
			(end 0.925 -0.47)
			(stroke
				(width 0.05)
				(type default)
			)
			(fill no)
			(layer "B.CrtYd")
		)
		(fp_rect
			(start -0.5 0.25)
			(end 0.5 -0.25)
			(stroke
				(width 0.15)
				(type solid)
			)
			(fill no)
			(layer "B.Fab")
		)
		(pad "1" smd roundrect
			(at -0.48 0)
			(size 0.59 0.64)
			(layers "B.Cu" "B.Mask" "B.Paste")
			(roundrect_rratio 0.25)
			(net 1 "GND")
			(pintype "passive")
			(teardrops
				(best_length_ratio 0.2)
				(max_length 1)
				(best_width_ratio 0.9)
				(max_width 2)
				(curved_edges yes)
				(filter_ratio 0.9)
				(enabled yes)
				(allow_two_segments yes)
				(prefer_zone_connections yes)
			)
		)
		(pad "2" smd roundrect
			(at 0.48 0)
			(size 0.59 0.64)
			(layers "B.Cu" "B.Mask" "B.Paste")
			(roundrect_rratio 0.25)
			(net 675 "Net-(U45C-GPI0)")
			(pintype "passive")
			(teardrops
				(best_length_ratio 0.2)
				(max_length 1)
				(best_width_ratio 0.9)
				(max_width 2)
				(curved_edges yes)
				(filter_ratio 0.9)
				(enabled yes)
				(allow_two_segments yes)
				(prefer_zone_connections yes)
			)
		)
	)
	(footprint "antmicro-footprints:R_0402_1005Metric"
		(layer "B.Cu")
		(at 99.3 75.81)
		(descr "Resistor SMD 0402")
		(tags "resistor SMD 0402")
		(property "Reference" "R153"
			(at -3.65 0.4 0)
			(layer "B.SilkS")
			(effects
				(font
					(size 0.7 0.7)
					(thickness 0.15)
				)
				(justify right bottom mirror)
			)
		)
		(property "Value" "R_10k_0402"
			(at -1.011843 -1.772047 0)
			(layer "B.Fab")
			(effects
				(font
					(size 0.7 0.7)
					(thickness 0.15)
				)
				(justify right bottom mirror)
			)
		)
		(property "Datasheet" "https://www.bourns.com/docs/product-datasheets/cr.pdf"
			(at 0 0 0)
			(layer "F.Fab")
			(hide yes)
			(effects
				(font
					(size 1.27 1.27)
					(thickness 0.15)
				)
			)
		)
		(property "Description" "SMD Chip Resistor, 10 kohm, ± 1%, 62.5 mW, 0402 [1005 Metric], Thick Film, General Purpose"
			(at 0 0 0)
			(layer "F.Fab")
			(hide yes)
			(effects
				(font
					(size 1.27 1.27)
					(thickness 0.15)
				)
			)
		)
		(property "Author" "Antmicro"
			(at 0 0 0)
			(layer "B.Fab")
			(hide yes)
			(effects
				(font
					(size 1 1)
					(thickness 0.15)
				)
				(justify mirror)
			)
		)
		(property "License" "Apache-2.0"
			(at 0 0 0)
			(layer "B.Fab")
			(hide yes)
			(effects
				(font
					(size 1 1)
					(thickness 0.15)
				)
				(justify mirror)
			)
		)
		(property "MPN" "CR0402-FX-1002GLF"
			(at 0 0 0)
			(layer "B.Fab")
			(hide yes)
			(effects
				(font
					(size 1 1)
					(thickness 0.15)
				)
				(justify mirror)
			)
		)
		(property "Manufacturer" "Bourns"
			(at 0 0 0)
			(layer "B.Fab")
			(hide yes)
			(effects
				(font
					(size 1 1)
					(thickness 0.15)
				)
				(justify mirror)
			)
		)
		(property "Tolerance" "1%"
			(at 0 0 0)
			(layer "B.Fab")
			(hide yes)
			(effects
				(font
					(size 1 1)
					(thickness 0.15)
				)
				(justify mirror)
			)
		)
		(property "Val" "10k"
			(at 0 0 0)
			(layer "B.Fab")
			(hide yes)
			(effects
				(font
					(size 1 1)
					(thickness 0.15)
				)
				(justify mirror)
			)
		)
		(sheetname "Misc")
		(sheetfile "misc.kicad_sch")
		(attr smd)
		(fp_rect
			(start -0.925 0.47)
			(end 0.925 -0.47)
			(stroke
				(width 0.05)
				(type default)
			)
			(fill no)
			(layer "B.CrtYd")
		)
		(fp_rect
			(start -0.5 0.25)
			(end 0.5 -0.25)
			(stroke
				(width 0.15)
				(type solid)
			)
			(fill no)
			(layer "B.Fab")
		)
		(pad "1" smd roundrect
			(at -0.48 0)
			(size 0.59 0.64)
			(layers "B.Cu" "B.Mask" "B.Paste")
			(roundrect_rratio 0.25)
			(net 540 "Net-(Q8-D)")
			(pintype "passive")
			(teardrops
				(best_length_ratio 0.2)
				(max_length 1)
				(best_width_ratio 0.9)
				(max_width 2)
				(curved_edges yes)
				(filter_ratio 0.9)
				(enabled yes)
				(allow_two_segments yes)
				(prefer_zone_connections yes)
			)
		)
		(pad "2" smd roundrect
			(at 0.48 0)
			(size 0.59 0.64)
			(layers "B.Cu" "B.Mask" "B.Paste")
			(roundrect_rratio 0.25)
			(net 132 "Net-(D18-C_{R})")
			(pintype "passive")
			(teardrops
				(best_length_ratio 0.2)
				(max_length 1)
				(best_width_ratio 0.9)
				(max_width 2)
				(curved_edges yes)
				(filter_ratio 0.9)
				(enabled yes)
				(allow_two_segments yes)
				(prefer_zone_connections yes)
			)
		)
	)
	(footprint "antmicro-footprints:R_0402_1005Metric"
		(layer "B.Cu")
		(at 123.4 100.86 180)
		(descr "Resistor SMD 0402")
		(tags "resistor SMD 0402")
		(property "Reference" "R330"
			(at -3.74 -0.44 0)
			(layer "B.SilkS")
			(effects
				(font
					(size 0.7 0.7)
					(thickness 0.15)
				)
				(justify left bottom mirror)
			)
		)
		(property "Value" "R_470R_0402"
			(at -1.011843 -1.772047 0)
			(layer "B.Fab")
			(effects
				(font
					(size 0.7 0.7)
					(thickness 0.15)
				)
				(justify left bottom mirror)
			)
		)
		(property "Datasheet" "https://www.bourns.com/docs/product-datasheets/cr.pdf"
			(at 0 0 0)
			(layer "B.Fab")
			(hide yes)
			(effects
				(font
					(size 1.27 1.27)
					(thickness 0.15)
				)
				(justify mirror)
			)
		)
		(property "MPN" "CR0402-FX-4700GLF"
			(at 0 0 0)
			(unlocked yes)
			(layer "B.Fab")
			(hide yes)
			(effects
				(font
					(size 1 1)
					(thickness 0.15)
				)
				(justify mirror)
			)
		)
		(property "Manufacturer" "Bourns"
			(at 0 0 0)
			(unlocked yes)
			(layer "B.Fab")
			(hide yes)
			(effects
				(font
					(size 1 1)
					(thickness 0.15)
				)
				(justify mirror)
			)
		)
		(property "License" "Apache-2.0"
			(at 0 0 0)
			(unlocked yes)
			(layer "B.Fab")
			(hide yes)
			(effects
				(font
					(size 1 1)
					(thickness 0.15)
				)
				(justify mirror)
			)
		)
		(property "Author" "Antmicro"
			(at 0 0 0)
			(unlocked yes)
			(layer "B.Fab")
			(hide yes)
			(effects
				(font
					(size 1 1)
					(thickness 0.15)
				)
				(justify mirror)
			)
		)
		(property "Val" "470R"
			(at 0 0 0)
			(unlocked yes)
			(layer "B.Fab")
			(hide yes)
			(effects
				(font
					(size 1 1)
					(thickness 0.15)
				)
				(justify mirror)
			)
		)
		(property "Tolerance" "1%"
			(at 0 0 0)
			(unlocked yes)
			(layer "B.Fab")
			(hide yes)
			(effects
				(font
					(size 1 1)
					(thickness 0.15)
				)
				(justify mirror)
			)
		)
		(property "Public" "False"
			(at 0 0 0)
			(unlocked yes)
			(layer "B.Fab")
			(hide yes)
			(effects
				(font
					(size 1 1)
					(thickness 0.15)
				)
				(justify mirror)
			)
		)
		(sheetname "2xUSB3.0+RJ45")
		(sheetfile "usb3+rj45.kicad_sch")
		(attr smd)
		(fp_rect
			(start -0.925 0.47)
			(end 0.925 -0.47)
			(stroke
				(width 0.05)
				(type default)
			)
			(fill no)
			(layer "B.CrtYd")
		)
		(fp_rect
			(start -0.5 0.25)
			(end 0.5 -0.25)
			(stroke
				(width 0.15)
				(type solid)
			)
			(fill no)
			(layer "B.Fab")
		)
		(pad "1" smd roundrect
			(at -0.48 0 180)
			(size 0.59 0.64)
			(layers "B.Cu" "B.Mask" "B.Paste")
			(roundrect_rratio 0.25)
			(net 1 "GND")
			(pintype "passive")
			(teardrops
				(best_length_ratio 0.2)
				(max_length 1)
				(best_width_ratio 0.9)
				(max_width 2)
				(curved_edges yes)
				(filter_ratio 0.9)
				(enabled yes)
				(allow_two_segments yes)
				(prefer_zone_connections yes)
			)
		)
		(pad "2" smd roundrect
			(at 0.48 0 180)
			(size 0.59 0.64)
			(layers "B.Cu" "B.Mask" "B.Paste")
			(roundrect_rratio 0.25)
			(net 155 "Net-(J1A-LED_D2)")
			(pintype "passive")
			(teardrops
				(best_length_ratio 0.2)
				(max_length 1)
				(best_width_ratio 0.9)
				(max_width 2)
				(curved_edges yes)
				(filter_ratio 0.9)
				(enabled yes)
				(allow_two_segments yes)
				(prefer_zone_connections yes)
			)
		)
	)
	(footprint "antmicro-footprints:R_0402_1005Metric"
		(layer "B.Cu")
		(at 123.4 96.86)
		(descr "Resistor SMD 0402")
		(tags "resistor SMD 0402")
		(property "Reference" "R7"
			(at 0.9 0.45 0)
			(layer "B.SilkS")
			(effects
				(font
					(size 0.7 0.7)
					(thickness 0.15)
				)
				(justify right bottom mirror)
			)
		)
		(property "Value" "R_470R_0402"
			(at -1.011843 -1.772047 0)
			(layer "B.Fab")
			(effects
				(font
					(size 0.7 0.7)
					(thickness 0.15)
				)
				(justify right bottom mirror)
			)
		)
		(property "Datasheet" "https://www.bourns.com/docs/product-datasheets/cr.pdf"
			(at 0 0 0)
			(layer "F.Fab")
			(hide yes)
			(effects
				(font
					(size 1.27 1.27)
					(thickness 0.15)
				)
			)
		)
		(property "Author" "Antmicro"
			(at 0 0 0)
			(layer "B.Fab")
			(hide yes)
			(effects
				(font
					(size 1 1)
					(thickness 0.15)
				)
				(justify mirror)
			)
		)
		(property "License" "Apache-2.0"
			(at 0 0 0)
			(layer "B.Fab")
			(hide yes)
			(effects
				(font
					(size 1 1)
					(thickness 0.15)
				)
				(justify mirror)
			)
		)
		(property "MPN" "CR0402-FX-4700GLF"
			(at 0 0 0)
			(layer "B.Fab")
			(hide yes)
			(effects
				(font
					(size 1 1)
					(thickness 0.15)
				)
				(justify mirror)
			)
		)
		(property "Manufacturer" "Bourns"
			(at 0 0 0)
			(layer "B.Fab")
			(hide yes)
			(effects
				(font
					(size 1 1)
					(thickness 0.15)
				)
				(justify mirror)
			)
		)
		(property "Public" "False"
			(at 0 0 0)
			(layer "B.Fab")
			(hide yes)
			(effects
				(font
					(size 1 1)
					(thickness 0.15)
				)
				(justify mirror)
			)
		)
		(property "Tolerance" "1%"
			(at 0 0 0)
			(layer "B.Fab")
			(hide yes)
			(effects
				(font
					(size 1 1)
					(thickness 0.15)
				)
				(justify mirror)
			)
		)
		(property "Val" "470R"
			(at 0 0 0)
			(layer "B.Fab")
			(hide yes)
			(effects
				(font
					(size 1 1)
					(thickness 0.15)
				)
				(justify mirror)
			)
		)
		(sheetname "2xUSB3.0+RJ45")
		(sheetfile "usb3+rj45.kicad_sch")
		(attr smd dnp)
		(fp_rect
			(start -0.925 0.47)
			(end 0.925 -0.47)
			(stroke
				(width 0.05)
				(type default)
			)
			(fill no)
			(layer "B.CrtYd")
		)
		(fp_rect
			(start -0.5 0.25)
			(end 0.5 -0.25)
			(stroke
				(width 0.15)
				(type solid)
			)
			(fill no)
			(layer "B.Fab")
		)
		(pad "1" smd roundrect
			(at -0.48 0)
			(size 0.59 0.64)
			(layers "B.Cu" "B.Mask" "B.Paste")
			(roundrect_rratio 0.25)
			(net 154 "Net-(J1A-LED_D1)")
			(pintype "passive")
			(teardrops
				(best_length_ratio 0.2)
				(max_length 1)
				(best_width_ratio 0.9)
				(max_width 2)
				(curved_edges yes)
				(filter_ratio 0.9)
				(enabled yes)
				(allow_two_segments yes)
				(prefer_zone_connections yes)
			)
		)
		(pad "2" smd roundrect
			(at 0.48 0)
			(size 0.59 0.64)
			(layers "B.Cu" "B.Mask" "B.Paste")
			(roundrect_rratio 0.25)
			(net 2 "+3V3")
			(pintype "passive")
			(teardrops
				(best_length_ratio 0.2)
				(max_length 1)
				(best_width_ratio 0.9)
				(max_width 2)
				(curved_edges yes)
				(filter_ratio 0.9)
				(enabled yes)
				(allow_two_segments yes)
				(prefer_zone_connections yes)
			)
		)
	)
)
